# T6G (Grand Teton) — schematic netlist excerpt (pin names and nets, part order shuffled) for the footprints in the layout excerpt that follows; sources: Cadence DE-HDL packaged netlist, KiCad conversion of 04192023_DAF0TMB3IC0_F0TG_MB_C_brd_V02_OCP.brd

PC336  Q_CAPP  270UF 16V 20% OSCON  pkg THLF  page 215 : A = SW_P12V_AUX_PVDDCR_SOC_P1_FLT ; B = GND
PC2091  Q_CAP  0.1UF 25V 10% X7R  pkg 0402  page 134 : A = P3V3_OCP_SFF_R ; B = GND
R1624  Q_RES  1K 1% CHIP  pkg 0402LF  page 172 : A = PVDD18_S5_P0 ; B = HDT_HDR_TCK

(kicad_pcb
	(version 20260206)
	(generator "pcbnew")
	(generator_version "10.0")
	(general
		(thickness 1.6)
		(legacy_teardrops no)
	)
	(paper "A4")
	(title_block
		(title "04192023_DAF0TMB3IC0_F0TG_MB_C_brd_V02_OCP.brd")
		(comment 1 "Grand Teton / footprints 2551-2553 of 8354")
	)
	(layers
		(0 "F.Cu" signal "TOP")
		(4 "In1.Cu" signal "GND")
		(6 "In2.Cu" signal "IN1")
		(8 "In3.Cu" signal "GND1")
		(10 "In4.Cu" signal "IN2")
		(12 "In5.Cu" signal "GND2")
		(14 "In6.Cu" signal "IN3")
		(16 "In7.Cu" signal "GND3")
		(18 "In8.Cu" signal "VCC")
		(20 "In9.Cu" signal "VCC1")
		(22 "In10.Cu" signal "GND4")
		(24 "In11.Cu" signal "IN4")
		(26 "In12.Cu" signal "GND5")
		(28 "In13.Cu" signal "IN5")
		(30 "In14.Cu" signal "GND6")
		(32 "In15.Cu" signal "IN6")
		(34 "In16.Cu" signal "GND7")
		(2 "B.Cu" signal "BOTTOM")
		(9 "F.Adhes" user "F.Adhesive")
		(11 "B.Adhes" user "B.Adhesive")
		(13 "F.Paste" user "Package Geometry/Pastemask Top")
		(15 "B.Paste" user "Package Geometry/Pastemask Bottom")
		(5 "F.SilkS" user "Ref Des/Silkscreen Top")
		(7 "B.SilkS" user "Ref Des/Silkscreen Bottom")
		(1 "F.Mask" user "Board Geometry/Soldermask Top")
		(3 "B.Mask" user "Board Geometry/Soldermask Bottom")
		(17 "Dwgs.User" user "User.Drawings")
		(19 "Cmts.User" user "User.Comments")
		(21 "Eco1.User" user "User.Eco1")
		(23 "Eco2.User" user "User.Eco2")
		(25 "Edge.Cuts" user "Board Geometry/Outline")
		(27 "Margin" user)
		(31 "F.CrtYd" user "Package Geometry/Place Bound Top")
		(29 "B.CrtYd" user "Package Geometry/Place Bound Bottom")
		(35 "F.Fab" user "Ref Des/Assembly Top")
		(33 "B.Fab" user "Ref Des/Assembly Bottom")
	)
	(footprint ""
		(layer "F.Cu")
		(at 271.800574 -93.927168 180)
		(property "Reference" "R1624"
			(at 0 0 180)
			(layer "F.SilkS")
			(hide yes)
			(effects
				(font
					(size 1.27 1.27)
				)
			)
		)
		(property "Value" ""
			(at 0 0 180)
			(layer "F.Fab")
			(effects
				(font
					(size 1.27 1.27)
				)
			)
		)
		(duplicate_pad_numbers_are_jumpers no)
		(fp_line
			(start 0.7874 0.4064)
			(end -0.7874 0.4064)
			(stroke
				(width 0.1524)
				(type default)
			)
			(layer "F.SilkS")
		)
		(fp_line
			(start 0.7874 -0.4064)
			(end 0.7874 0.4064)
			(stroke
				(width 0.1524)
				(type default)
			)
			(layer "F.SilkS")
		)
		(fp_line
			(start -0.7874 0.4064)
			(end -0.7874 -0.4064)
			(stroke
				(width 0.1524)
				(type default)
			)
			(layer "F.SilkS")
		)
		(fp_line
			(start -0.7874 -0.4064)
			(end 0.7874 -0.4064)
			(stroke
				(width 0.1524)
				(type default)
			)
			(layer "F.SilkS")
		)
		(fp_line
			(start 0.67945 0.3048)
			(end 0.120396 0.3048)
			(stroke
				(width 0.1)
				(type default)
			)
			(layer "F.Fab")
		)
		(fp_line
			(start 0.67945 -0.3048)
			(end 0.67945 0.3048)
			(stroke
				(width 0.1)
				(type default)
			)
			(layer "F.Fab")
		)
		(fp_line
			(start 0.12065 -0.2794)
			(end 0.12065 -0.3048)
			(stroke
				(width 0.1)
				(type default)
			)
			(layer "F.Fab")
		)
		(fp_line
			(start 0.12065 -0.3048)
			(end 0.67945 -0.3048)
			(stroke
				(width 0.1)
				(type default)
			)
			(layer "F.Fab")
		)
		(fp_line
			(start 0.120396 0.3048)
			(end 0.120396 0.2794)
			(stroke
				(width 0.1)
				(type default)
			)
			(layer "F.Fab")
		)
		(fp_line
			(start 0.120396 0.2794)
			(end -0.12065 0.2794)
			(stroke
				(width 0.1)
				(type default)
			)
			(layer "F.Fab")
		)
		(fp_line
			(start -0.12065 0.3048)
			(end -0.67945 0.3048)
			(stroke
				(width 0.1)
				(type default)
			)
			(layer "F.Fab")
		)
		(fp_line
			(start -0.12065 0.2794)
			(end -0.12065 0.3048)
			(stroke
				(width 0.1)
				(type default)
			)
			(layer "F.Fab")
		)
		(fp_line
			(start -0.12065 -0.2794)
			(end 0.12065 -0.2794)
			(stroke
				(width 0.1)
				(type default)
			)
			(layer "F.Fab")
		)
		(fp_line
			(start -0.12065 -0.305054)
			(end -0.12065 -0.2794)
			(stroke
				(width 0.1)
				(type default)
			)
			(layer "F.Fab")
		)
		(fp_line
			(start -0.67945 0.3048)
			(end -0.67945 -0.305054)
			(stroke
				(width 0.1)
				(type default)
			)
			(layer "F.Fab")
		)
		(fp_line
			(start -0.67945 -0.305054)
			(end -0.12065 -0.305054)
			(stroke
				(width 0.1)
				(type default)
			)
			(layer "F.Fab")
		)
		(pad "1" smd circle
			(at -0.40005 0 180)
			(size 0 0)
			(layers "F.Cu" "F.Mask" "F.Paste")
			(net "PVDD18_S5_P0")
		)
		(pad "2" smd circle
			(at 0.40005 0 180)
			(size 0 0)
			(layers "F.Cu" "F.Mask" "F.Paste")
			(net "HDT_HDR_TCK")
		)
	)
	(footprint ""
		(layer "F.Cu")
		(at 110.140496 -150.941786 90)
		(property "Reference" "PC336"
			(at 4.185666 -0.65151 0)
			(unlocked yes)
			(layer "F.SilkS")
			(effects
				(font
					(size 0.7874 0.5842)
					(thickness 0.1524)
				)
				(justify left)
			)
		)
		(property "Value" ""
			(at 0 0 90)
			(layer "F.Fab")
			(effects
				(font
					(size 1.27 1.27)
				)
			)
		)
		(duplicate_pad_numbers_are_jumpers no)
		(fp_line
			(start -3.400044 1.249934)
			(end 3.400044 1.249934)
			(stroke
				(width 0.1524)
				(type default)
			)
			(layer "F.SilkS")
		)
		(fp_circle
			(center 0 1.249934)
			(end 0 4.649978)
			(stroke
				(width 0.1524)
				(type default)
			)
			(fill no)
			(layer "F.SilkS")
		)
		(fp_poly
			(pts
				(arc
					(start 3.400044 1.249934)
					(mid 0 4.649978)
					(end -3.400044 1.249934)
				)
			)
			(stroke
				(width 0)
				(type default)
			)
			(fill yes)
			(layer "F.SilkS")
		)
		(fp_circle
			(center 0 1.249934)
			(end 0 4.649978)
			(stroke
				(width 0.1)
				(type default)
			)
			(fill no)
			(layer "F.Fab")
		)
		(pad "1" thru_hole rect
			(at 0 0 90)
			(size 1.524 1.524)
			(drill 1.016)
			(layers "*.Cu" "*.Mask")
			(remove_unused_layers no)
			(net "SW_P12V_AUX_PVDDCR_SOC_P1_FLT")
			(clearance 0)
			(padstack
				(mode front_inner_back)
				(layer "Inner"
					(shape circle)
					(size 1.524 1.524)
					(clearance 0)
				)
				(layer "B.Cu"
					(shape rect)
					(size 1.524 1.524)
					(clearance 0)
				)
			)
		)
		(pad "2" thru_hole circle
			(at 0 2.500122 90)
			(size 1.524 1.524)
			(drill 1.016)
			(layers "*.Cu" "*.Mask")
			(remove_unused_layers no)
			(net "GND")
			(clearance 0)
		)
	)
	(footprint ""
		(layer "F.Cu")
		(at 425.163488 -109.12983 90)
		(property "Reference" "PC2091"
			(at 0 0 90)
			(layer "F.SilkS")
			(hide yes)
			(effects
				(font
					(size 1.27 1.27)
				)
			)
		)
		(property "Value" ""
			(at 0 0 90)
			(layer "F.Fab")
			(effects
				(font
					(size 1.27 1.27)
				)
			)
		)
		(duplicate_pad_numbers_are_jumpers no)
		(fp_line
			(start 0.7874 -0.4064)
			(end 0.7874 0.4064)
			(stroke
				(width 0.1524)
				(type default)
			)
			(layer "F.SilkS")
		)
		(fp_line
			(start -0.7874 -0.4064)
			(end 0.7874 -0.4064)
			(stroke
				(width 0.1524)
				(type default)
			)
			(layer "F.SilkS")
		)
		(fp_line
			(start 0.7874 0.4064)
			(end -0.7874 0.4064)
			(stroke
				(width 0.1524)
				(type default)
			)
			(layer "F.SilkS")
		)
		(fp_line
			(start -0.7874 0.4064)
			(end -0.7874 -0.4064)
			(stroke
				(width 0.1524)
				(type default)
			)
			(layer "F.SilkS")
		)
		(fp_line
			(start -0.12065 -0.305054)
			(end -0.12065 -0.2794)
			(stroke
				(width 0.1)
				(type default)
			)
			(layer "F.Fab")
		)
		(fp_line
			(start -0.67945 -0.305054)
			(end -0.12065 -0.305054)
			(stroke
				(width 0.1)
				(type default)
			)
			(layer "F.Fab")
		)
		(fp_line
			(start 0.67945 -0.3048)
			(end 0.67945 0.3048)
			(stroke
				(width 0.1)
				(type default)
			)
			(layer "F.Fab")
		)
		(fp_line
			(start 0.12065 -0.3048)
			(end 0.67945 -0.3048)
			(stroke
				(width 0.1)
				(type default)
			)
			(layer "F.Fab")
		)
		(fp_line
			(start 0.12065 -0.2794)
			(end 0.12065 -0.3048)
			(stroke
				(width 0.1)
				(type default)
			)
			(layer "F.Fab")
		)
		(fp_line
			(start -0.12065 -0.2794)
			(end 0.12065 -0.2794)
			(stroke
				(width 0.1)
				(type default)
			)
			(layer "F.Fab")
		)
		(fp_line
			(start 0.120396 0.2794)
			(end -0.12065 0.2794)
			(stroke
				(width 0.1)
				(type default)
			)
			(layer "F.Fab")
		)
		(fp_line
			(start -0.12065 0.2794)
			(end -0.12065 0.3048)
			(stroke
				(width 0.1)
				(type default)
			)
			(layer "F.Fab")
		)
		(fp_line
			(start 0.67945 0.3048)
			(end 0.120396 0.3048)
			(stroke
				(width 0.1)
				(type default)
			)
			(layer "F.Fab")
		)
		(fp_line
			(start 0.120396 0.3048)
			(end 0.120396 0.2794)
			(stroke
				(width 0.1)
				(type default)
			)
			(layer "F.Fab")
		)
		(fp_line
			(start -0.12065 0.3048)
			(end -0.67945 0.3048)
			(stroke
				(width 0.1)
				(type default)
			)
			(layer "F.Fab")
		)
		(fp_line
			(start -0.67945 0.3048)
			(end -0.67945 -0.305054)
			(stroke
				(width 0.1)
				(type default)
			)
			(layer "F.Fab")
		)
		(pad "1" smd circle
			(at -0.40005 0 90)
			(size 0 0)
			(layers "F.Cu" "F.Mask" "F.Paste")
			(net "P3V3_OCP_SFF_R")
		)
		(pad "2" smd circle
			(at 0.40005 0 90)
			(size 0 0)
			(layers "F.Cu" "F.Mask" "F.Paste")
			(net "GND")
		)
	)
)
